# S9S_MB_2U (Grand Teton) — schematic netlist excerpt (pin names and nets, part order shuffled) for the footprints in the layout excerpt that follows; sources: Cadence DE-HDL packaged netlist, KiCad conversion of 03242023_DA0F0TMBIJ0_F0T_Motherboard_J_brd_V01_OCP.brd

J30  SCONN288_ADR50017P087CC  SCONN288_ADR50017-P087CC IO  pkg DDR288S_1-1VXB  page 111
  VIN_BULK0  = P12V_S3_AUX_CPU1_NVDIMM
  RFU0  = TP_CHG_CPU1_DIMM2_FRU_0
  VIN_MGMT  = P3V3_AUX
  HSCL  = I3C_SPD_DDREFGH_CPU1_LVC1_SCL_5
  HSDA  = I3C_SPD_DDREFGH_CPU1_LVC1_SDA
  VSS0  = GND
  DQ0_A  = M_G_CPU1_SA_DQ<0>
  VSS1  = GND
  DQ1_A  = M_G_CPU1_SA_DQ<1>
  VSS2  = GND
  DQS0_A_T  = M_G_CPU1_SA_DQS_DP<0>
  DQS0_A_C  = M_G_CPU1_SA_DQS_DN<0>
  VSS3  = GND
  DQ4_A  = M_G_CPU1_SA_DQ<4>
  VSS4  = GND
  DQ5_A  = M_G_CPU1_SA_DQ<5>
  VSS5  = GND
  DQ8_A  = M_G_CPU1_SA_DQ<8>
  VSS6  = GND
  DQ9_A  = M_G_CPU1_SA_DQ<9>
  VSS7  = GND
  DQS1_A_T  = M_G_CPU1_SA_DQS_DP<1>
  DQS1_A_C  = M_G_CPU1_SA_DQS_DN<1>
  VSS8  = GND
  DQ12_A  = M_G_CPU1_SA_DQ<12>
  VSS9  = GND
  DQ13_A  = M_G_CPU1_SA_DQ<13>
  VSS10  = GND
  DQ16_A  = M_G_CPU1_SA_DQ<16>
  VSS11  = GND
  DQ17_A  = M_G_CPU1_SA_DQ<17>
  VSS12  = GND
  DQS2_A_T  = M_G_CPU1_SA_DQS_DP<2>
  DQS2_A_C  = M_G_CPU1_SA_DQS_DN<2>
  VSS13  = GND
  DQ20_A  = M_G_CPU1_SA_DQ<20>
  VSS14  = GND
  DQ21_A  = M_G_CPU1_SA_DQ<21>
  VSS15  = GND
  DQ24_A  = M_G_CPU1_SA_DQ<24>
  VSS16  = GND
  DQ25_A  = M_G_CPU1_SA_DQ<25>
  VSS17  = GND
  DQS3_A_T  = M_G_CPU1_SA_DQS_DP<3>
  DQS3_A_C  = M_G_CPU1_SA_DQS_DN<3>
  VSS18  = GND
  DQ28_A  = M_G_CPU1_SA_DQ<28>
  VSS19  = GND
  DQ29_A  = M_G_CPU1_SA_DQ<29>
  VSS20  = GND
  CB0_A  = M_G_CPU1_SA_CB<0>
  VSS21  = GND
  CB1_A  = M_G_CPU1_SA_CB<1>
  VSS22  = GND
  DQS4_A_T  = M_G_CPU1_SA_DQS_DP<4>
  DQS4_A_C  = M_G_CPU1_SA_DQS_DN<4>
  VSS23  = GND
  CB4_A  = M_G_CPU1_SA_CB<4>
  VSS24  = GND
  CB5_A  = M_G_CPU1_SA_CB<5>
  VSS25  = GND
  ALERT_N  = M_G_CPU1_ALERT_N
  VSS26  = GND
  CS0_A_N  = M_G_CPU1_SA_CS_N<2>
  VSS27  = GND
  CA0_A  = M_G_CPU1_SA_CA<0>
  VSS28  = GND
  CA2_A  = M_G_CPU1_SA_CA<2>
  VSS29  = GND
  CA4_A  = M_G_CPU1_SA_CA<4>
  VSS30  = GND
  CA6_A  = M_G_CPU1_SA_CA<6>
  VSS31  = GND
  PAR_A  = M_G_CPU1_SA_PAR
  VSS32  = GND
  CA0_B  = M_G_CPU1_SB_CA<0>
  VSS33  = GND
  CA2_B  = M_G_CPU1_SB_CA<2>
  VSS34  = GND
  CA4_B  = M_G_CPU1_SB_CA<4>
  VSS35  = GND
  CA6_B  = M_G_CPU1_SB_CA<6>
  VSS36  = GND
  CS0_B_N  = M_G_CPU1_SB_CS_N<2>
  VSS37  = GND
  \lbd||rsp_a_n\  = M_G_CPU1_SA_RSP<1>
  \lbs||rsp_b_n\  = M_G_CPU1_SB_RSP<1>
  VSS38  = GND
  CB4_B  = M_G_CPU1_SB_CB<4>
  VSS39  = GND
  CB5_B  = M_G_CPU1_SB_CB<5>
  VSS40  = GND
  \dqs9_b_t||tdqs9_b_t||dbi4_b_n\  = M_G_CPU1_SB_DQS_DP<9>
  \dqs9_b_c||tdqs9_b_c\  = M_G_CPU1_SB_DQS_DN<9>
  VSS41  = GND
  CB0_B  = M_G_CPU1_SB_CB<0>
  VSS42  = GND
  CB1_B  = M_G_CPU1_SB_CB<1>
  VSS43  = GND
  DQ0_B  = M_G_CPU1_SB_DQ<0>
  VSS44  = GND
  DQ1_B  = M_G_CPU1_SB_DQ<1>
  VSS45  = GND
  DQS0_B_T  = M_G_CPU1_SB_DQS_DP<0>
  DQS0_B_C  = M_G_CPU1_SB_DQS_DN<0>
  VSS46  = GND
  DQ4_B  = M_G_CPU1_SB_DQ<4>
  VSS47  = GND
  DQ5_B  = M_G_CPU1_SB_DQ<5>
  VSS48  = GND
  DQ8_B  = M_G_CPU1_SB_DQ<8>
  VSS49  = GND
  DQ9_B  = M_G_CPU1_SB_DQ<9>
  VSS50  = GND
  DQS1_B_T  = M_G_CPU1_SB_DQS_DP<1>
  DQS1_B_C  = M_G_CPU1_SB_DQS_DN<1>
  VSS51  = GND
  DQ12_B  = M_G_CPU1_SB_DQ<12>
  VSS52  = GND
  DQ13_B  = M_G_CPU1_SB_DQ<13>
  VSS53  = GND
  DQ16_B  = M_G_CPU1_SB_DQ<16>
  VSS54  = GND
  DQ17_B  = M_G_CPU1_SB_DQ<17>
  VSS55  = GND
  DQS2_B_T  = M_G_CPU1_SB_DQS_DP<2>
  DQS2_B_C  = M_G_CPU1_SB_DQS_DN<2>
  VSS56  = GND
  DQ20_B  = M_G_CPU1_SB_DQ<20>
  VSS57  = GND
  DQ21_B  = M_G_CPU1_SB_DQ<21>
  VSS58  = GND
  DQ24_B  = M_G_CPU1_SB_DQ<24>
  VSS59  = GND
  DQ25_B  = M_G_CPU1_SB_DQ<25>
  VSS60  = GND
  DQS3_B_T  = M_G_CPU1_SB_DQS_DP<3>
  DQS3_B_C  = M_G_CPU1_SB_DQS_DN<3>
  VSS61  = GND
  DQ28_B  = M_G_CPU1_SB_DQ<28>
  VSS62  = GND
  DQ29_B  = M_G_CPU1_SB_DQ<29>
  VSS63  = GND
  RFU1  = TP_CHG_CPU1_DIMM2_FRU_1
  VIN_BULK1  = P12V_S3_AUX_CPU1_NVDIMM
  VIN_BULK2  = P12V_S3_AUX_CPU1_NVDIMM
  \pwr_good||fail_n\  = PWRGD_CHG_CPU1_DIMM2
  HSA  = PD_CHG_CPU1_DIMM2_SAA
  RFU2  = TP_CHG_CPU1_DIMM2_FRU_2
  RFU3  = TP_CHG_CPU1_DIMM2_FRU_3
  VSS64  = GND
  DQ2_A  = M_G_CPU1_SA_DQ<2>
  VSS65  = GND
  DQ3_A  = M_G_CPU1_SA_DQ<3>
  VSS66  = GND
  \dqs5_a_c||tdqs5_a_c||dqs5_a_t||tdqs5_a_t\  = M_G_CPU1_SA_DQS_DN<5>
  \dqs5_a_t||tdqs5_a_t\  = M_G_CPU1_SA_DQS_DP<5>
  VSS67  = GND
  DQ6_A  = M_G_CPU1_SA_DQ<6>
  VSS68  = GND
  DQ7_A  = M_G_CPU1_SA_DQ<7>
  VSS69  = GND
  DQ10_A  = M_G_CPU1_SA_DQ<10>
  VSS70  = GND
  DQ11_A  = M_G_CPU1_SA_DQ<11>
  VSS71  = GND
  \dqs6_a_c||tdqs6_a_c||dqs6_a_t||tdqs6_a_t\  = M_G_CPU1_SA_DQS_DN<6>
  \dqs6_a_t||tdqs6_a_t\  = M_G_CPU1_SA_DQS_DP<6>
  VSS72  = GND
  DQ14_A  = M_G_CPU1_SA_DQ<14>
  VSS73  = GND
  DQ15_A  = M_G_CPU1_SA_DQ<15>
  VSS74  = GND
  DQ18_A  = M_G_CPU1_SA_DQ<18>
  VSS75  = GND
  DQ19_A  = M_G_CPU1_SA_DQ<19>
  VSS76  = GND
  \dqs7_a_c||tdqs7_a_c\  = M_G_CPU1_SA_DQS_DN<7>
  \dqs7_a_t||tdqs7_a_t\  = M_G_CPU1_SA_DQS_DP<7>
  VSS77  = GND
  DQ22_A  = M_G_CPU1_SA_DQ<22>
  VSS78  = GND
  DQ23_A  = M_G_CPU1_SA_DQ<23>
  VSS79  = GND
  DQ26_A  = M_G_CPU1_SA_DQ<26>
  VSS80  = GND
  DQ27_A  = M_G_CPU1_SA_DQ<27>
  VSS81  = GND
  \dqs8_a_c||tdqs8_a_c\  = M_G_CPU1_SA_DQS_DN<8>
  \dqs8_a_t||tdqs8_a_t\  = M_G_CPU1_SA_DQS_DP<8>
  VSS82  = GND
  DQ30_A  = M_G_CPU1_SA_DQ<30>
  VSS83  = GND
  DQ31_A  = M_G_CPU1_SA_DQ<31>
  VSS84  = GND
  CB2_A  = M_G_CPU1_SA_CB<2>
  VSS85  = GND
  CB3_A  = M_G_CPU1_SA_CB<3>
  VSS86  = GND
  \dqs9_a_c||tdqs9_a_c\  = M_G_CPU1_SA_DQS_DN<9>
  \dqs9_a_t||tdqs9_a_t\  = M_G_CPU1_SA_DQS_DP<9>
  VSS87  = GND
  CB6_A  = M_G_CPU1_SA_CB<6>
  VSS88  = GND
  CB7_A  = M_G_CPU1_SA_CB<7>
  VSS89  = GND
  RESET_N  = RST_M_GH_CPU1_FPGA_N
  VSS90  = GND
  CS1_A_N  = M_G_CPU1_SA_CS_N<3>
  VSS91  = GND
  CA1_A  = M_G_CPU1_SA_CA<1>
  VSS92  = GND
  CA3_A  = M_G_CPU1_SA_CA<3>
  VSS93  = GND
  CA5_A  = M_G_CPU1_SA_CA<5>
  VSS94  = GND
  CK_T  = M_G_CPU1_CLK_DP<1>
  CK_C  = M_G_CPU1_CLK_DN<1>
  VSS95  = GND
  RFU4  = TP_CHG_CPU1_DIMM2_FRU_4
  CA1_B  = M_G_CPU1_SB_CA<1>
  VSS96  = GND
  CA3_B  = M_G_CPU1_SB_CA<3>
  VSS97  = GND
  CA5_B  = M_G_CPU1_SB_CA<5>
  VSS98  = GND
  PAR_B  = M_G_CPU1_SB_PAR
  VSS99  = GND
  CS1_B_N  = M_G_CPU1_SB_CS_N<3>
  VSS100  = GND
  RFU5  = TP_CHG_CPU1_DIMM2_FRU_5
  RFU6  = TP_CHG_CPU1_DIMM2_FRU_6
  VSS101  = GND
  CB6_B  = M_G_CPU1_SB_CB<6>
  VSS102  = GND
  CB7_B  = M_G_CPU1_SB_CB<7>
  VSS103  = GND
  DQS4_B_C  = M_G_CPU1_SB_DQS_DN<4>
  DQS4_B_T  = M_G_CPU1_SB_DQS_DP<4>
  VSS104  = GND
  CB2_B  = M_G_CPU1_SB_CB<2>
  VSS105  = GND
  CB3_B  = M_G_CPU1_SB_CB<3>
  VSS106  = GND
  DQ2_B  = M_G_CPU1_SB_DQ<2>
  VSS107  = GND
  DQ3_B  = M_G_CPU1_SB_DQ<3>
  VSS108  = GND
  \dqs5_b_c||tdqs5_b_c\  = M_G_CPU1_SB_DQS_DN<5>
  \dqs5_b_t||tdqs5_b_t\  = M_G_CPU1_SB_DQS_DP<5>
  VSS109  = GND
  DQ6_B  = M_G_CPU1_SB_DQ<6>
  VSS110  = GND
  DQ7_B  = M_G_CPU1_SB_DQ<7>
  VSS111  = GND
  DQ10_B  = M_G_CPU1_SB_DQ<10>
  VSS112  = GND
  DQ11_B  = M_G_CPU1_SB_DQ<11>
  VSS113  = GND
  \dqs6_b_c||tdqs6_b_c\  = M_G_CPU1_SB_DQS_DN<6>
  \dqs6_b_t||tdqs6_b_t\  = M_G_CPU1_SB_DQS_DP<6>
  VSS114  = GND
  DQ14_B  = M_G_CPU1_SB_DQ<14>
  VSS115  = GND
  DQ15_B  = M_G_CPU1_SB_DQ<15>
  VSS116  = GND
  DQ18_B  = M_G_CPU1_SB_DQ<18>
  VSS117  = GND
  DQ19_B  = M_G_CPU1_SB_DQ<19>
  VSS118  = GND
  \dqs7_b_c||tdqs7_b_c\  = M_G_CPU1_SB_DQS_DN<7>
  \dqs7_b_t||tdqs7_b_t\  = M_G_CPU1_SB_DQS_DP<7>
  VSS119  = GND
  DQ22_B  = M_G_CPU1_SB_DQ<22>
  VSS120  = GND
  DQ23_B  = M_G_CPU1_SB_DQ<23>
  VSS121  = GND
  DQ26_B  = M_G_CPU1_SB_DQ<26>
  VSS122  = GND
  DQ27_B  = M_G_CPU1_SB_DQ<27>
  VSS123  = GND
  \dqs8_b_c||tdqs8_b_c\  = M_G_CPU1_SB_DQS_DN<8>
  \dqs8_b_t||tdqs8_b_t\  = M_G_CPU1_SB_DQS_DP<8>
  VSS124  = GND
  DQ30_B  = M_G_CPU1_SB_DQ<30>
  VSS125  = GND
  DQ31_B  = M_G_CPU1_SB_DQ<31>
  VSS126  = GND
  G1  = GND
  G2  = GND
  G3  = GND

(kicad_pcb
	(version 20260206)
	(generator "pcbnew")
	(generator_version "10.0")
	(general
		(thickness 1.6)
		(legacy_teardrops no)
	)
	(paper "A4")
	(title_block
		(title "03242023_DA0F0TMBIJ0_F0T_Motherboard_J_brd_V01_OCP.brd")
		(comment 1 "Grand Teton / footprint 1354 of 6105 (J30), pads 275-291 of 291")
	)
	(layers
		(0 "F.Cu" signal "TOP")
		(4 "In1.Cu" signal "GND")
		(6 "In2.Cu" signal "IN1")
		(8 "In3.Cu" signal "GND1")
		(10 "In4.Cu" signal "IN2")
		(12 "In5.Cu" signal "GND2")
		(14 "In6.Cu" signal "IN3")
		(16 "In7.Cu" signal "GND3")
		(18 "In8.Cu" signal "VCC")
		(20 "In9.Cu" signal "VCC1")
		(22 "In10.Cu" signal "GND4")
		(24 "In11.Cu" signal "IN4")
		(26 "In12.Cu" signal "GND5")
		(28 "In13.Cu" signal "IN5")
		(30 "In14.Cu" signal "GND6")
		(32 "In15.Cu" signal "IN6")
		(34 "In16.Cu" signal "GND7")
		(2 "B.Cu" signal "BOTTOM")
		(9 "F.Adhes" user "F.Adhesive")
		(11 "B.Adhes" user "B.Adhesive")
		(13 "F.Paste" user "Package Geometry/Pastemask Top")
		(15 "B.Paste" user "Package Geometry/Pastemask Bottom")
		(5 "F.SilkS" user "Ref Des/Silkscreen Top")
		(7 "B.SilkS" user "Ref Des/Silkscreen Bottom")
		(1 "F.Mask" user "Board Geometry/Soldermask Top")
		(3 "B.Mask" user "Board Geometry/Soldermask Bottom")
		(17 "Dwgs.User" user "User.Drawings")
		(19 "Cmts.User" user "User.Comments")
		(21 "Eco1.User" user "User.Eco1")
		(23 "Eco2.User" user "User.Eco2")
		(25 "Edge.Cuts" user "Board Geometry/Outline")
		(27 "Margin" user)
		(31 "F.CrtYd" user "Package Geometry/Place Bound Top")
		(29 "B.CrtYd" user "Package Geometry/Place Bound Bottom")
		(35 "F.Fab" user "Ref Des/Assembly Top")
		(33 "B.Fab" user "Ref Des/Assembly Bottom")
	)
	(footprint ""
		(layer "F.Cu")
		(at 191.03848 -258.091686)
		(property "Reference" "J30"
			(at -2.98196 -81.740248 0)
			(unlocked yes)
			(layer "F.SilkS")
			(effects
				(font
					(size 0.7874 0.5842)
					(thickness 0.1524)
				)
				(justify left)
			)
		)
		(property "Value" ""
			(at 0 0 0)
			(layer "F.Fab")
			(effects
				(font
					(size 1.27 1.27)
				)
			)
		)
		(duplicate_pad_numbers_are_jumpers no)
		(pad "275" smd rect
			(at 2.050034 52.274978 270)
			(size 0.519938 1.4986)
			(layers "F.Cu" "F.Mask" "F.Paste")
			(net "GND")
		)
		(pad "276" smd rect
			(at 2.050034 53.125116 270)
			(size 0.519938 1.4986)
			(layers "F.Cu" "F.Mask" "F.Paste")
			(net "M_G_CPU1_SB_DQ<23>")
		)
		(pad "277" smd rect
			(at 2.050034 53.975 270)
			(size 0.519938 1.4986)
			(layers "F.Cu" "F.Mask" "F.Paste")
			(net "GND")
		)
		(pad "278" smd rect
			(at 2.050034 54.824884 270)
			(size 0.519938 1.4986)
			(layers "F.Cu" "F.Mask" "F.Paste")
			(net "M_G_CPU1_SB_DQ<26>")
		)
		(pad "279" smd rect
			(at 2.050034 55.675022 270)
			(size 0.519938 1.4986)
			(layers "F.Cu" "F.Mask" "F.Paste")
			(net "GND")
		)
		(pad "280" smd rect
			(at 2.050034 56.524906 270)
			(size 0.519938 1.4986)
			(layers "F.Cu" "F.Mask" "F.Paste")
			(net "M_G_CPU1_SB_DQ<27>")
		)
		(pad "281" smd rect
			(at 2.050034 57.375044 270)
			(size 0.519938 1.4986)
			(layers "F.Cu" "F.Mask" "F.Paste")
			(net "GND")
		)
		(pad "282" smd rect
			(at 2.050034 58.224928 270)
			(size 0.519938 1.4986)
			(layers "F.Cu" "F.Mask" "F.Paste")
			(net "M_G_CPU1_SB_DQS_DN<8>")
		)
		(pad "283" smd rect
			(at 2.050034 59.075066 270)
			(size 0.519938 1.4986)
			(layers "F.Cu" "F.Mask" "F.Paste")
			(net "M_G_CPU1_SB_DQS_DP<8>")
		)
		(pad "284" smd rect
			(at 2.050034 59.92495 270)
			(size 0.519938 1.4986)
			(layers "F.Cu" "F.Mask" "F.Paste")
			(net "GND")
		)
		(pad "285" smd rect
			(at 2.050034 60.775088 270)
			(size 0.519938 1.4986)
			(layers "F.Cu" "F.Mask" "F.Paste")
			(net "M_G_CPU1_SB_DQ<30>")
		)
		(pad "286" smd rect
			(at 2.050034 61.624972 270)
			(size 0.519938 1.4986)
			(layers "F.Cu" "F.Mask" "F.Paste")
			(net "GND")
		)
		(pad "287" smd rect
			(at 2.050034 62.47511 270)
			(size 0.519938 1.4986)
			(layers "F.Cu" "F.Mask" "F.Paste")
			(net "M_G_CPU1_SB_DQ<31>")
		)
		(pad "288" smd rect
			(at 2.050034 63.324994 270)
			(size 0.519938 1.4986)
			(layers "F.Cu" "F.Mask" "F.Paste")
			(net "GND")
		)
		(pad "G1" thru_hole oval
			(at 0 -68.97497)
			(size 2.8194 1.5748)
			(drill oval 2.4384 1.1938)
			(layers "*.Cu" "*.Mask")
			(remove_unused_layers no)
			(net "GND")
			(clearance 0.127)
			(thermal_gap 0.127)
		)
		(pad "G2" thru_hole oval
			(at 0 3.875024)
			(size 2.8194 1.5748)
			(drill oval 2.4384 1.1938)
			(layers "*.Cu" "*.Mask")
			(remove_unused_layers no)
			(net "GND")
			(clearance 0.127)
			(thermal_gap 0.127)
		)
		(pad "G3" thru_hole oval
			(at 0 68.97497)
			(size 2.8194 1.5748)
			(drill oval 2.4384 1.1938)
			(layers "*.Cu" "*.Mask")
			(remove_unused_layers no)
			(net "GND")
			(clearance 0.127)
			(thermal_gap 0.127)
		)
	)
)
